(kicad_pcb
	(version 20260206)
	(generator "pcbnew")
	(generator_version "10.0")
	(general
		(thickness 1.6)
		(legacy_teardrops no)
	)
	(paper "A4")
	(title_block
		(title "12092022_DA0F0TFB6D0_F0T_FAN_BOARD_MP5048_D_brd_v02_OCP.brd")
		(comment 1 "Grand Teton / footprints 497-503 of 924")
	)
	(layers
		(0 "F.Cu" signal "TOP")
		(4 "In1.Cu" signal "GND")
		(6 "In2.Cu" signal "IN1")
		(8 "In3.Cu" signal "IN2")
		(10 "In4.Cu" signal "GND1")
		(2 "B.Cu" signal "BOTTOM")
		(9 "F.Adhes" user "F.Adhesive")
		(11 "B.Adhes" user "B.Adhesive")
		(13 "F.Paste" user "Package Geometry/Pastemask Top")
		(15 "B.Paste" user "Package Geometry/Pastemask Bottom")
		(5 "F.SilkS" user "Ref Des/Silkscreen Top")
		(7 "B.SilkS" user "Ref Des/Silkscreen Bottom")
		(1 "F.Mask" user "Board Geometry/Soldermask Top")
		(3 "B.Mask" user "Board Geometry/Soldermask Bottom")
		(17 "Dwgs.User" user "User.Drawings")
		(19 "Cmts.User" user "User.Comments")
		(21 "Eco1.User" user "User.Eco1")
		(23 "Eco2.User" user "User.Eco2")
		(25 "Edge.Cuts" user "Board Geometry/Outline")
		(27 "Margin" user)
		(31 "F.CrtYd" user "Package Geometry/Place Bound Top")
		(29 "B.CrtYd" user "Package Geometry/Place Bound Bottom")
		(35 "F.Fab" user "Ref Des/Assembly Top")
		(33 "B.Fab" user "Ref Des/Assembly Bottom")
	)
	(footprint ""
		(layer "F.Cu")
		(at 19.177 -105.41 180)
		(property "Reference" "R5312"
			(at 0 0 180)
			(layer "F.SilkS")
			(hide yes)
			(effects
				(font
					(size 1.27 1.27)
				)
			)
		)
		(property "Value" ""
			(at 0 0 180)
			(layer "F.Fab")
			(effects
				(font
					(size 1.27 1.27)
				)
			)
		)
		(duplicate_pad_numbers_are_jumpers no)
		(fp_line
			(start 1.2954 0.5842)
			(end -1.2954 0.5842)
			(stroke
				(width 0.1524)
				(type default)
			)
			(layer "F.SilkS")
		)
		(fp_line
			(start 1.2954 -0.5842)
			(end 1.2954 0.5842)
			(stroke
				(width 0.1524)
				(type default)
			)
			(layer "F.SilkS")
		)
		(fp_line
			(start -1.2954 0.5842)
			(end -1.2954 -0.5842)
			(stroke
				(width 0.1524)
				(type default)
			)
			(layer "F.SilkS")
		)
		(fp_line
			(start -1.2954 -0.5842)
			(end 1.2954 -0.5842)
			(stroke
				(width 0.1524)
				(type default)
			)
			(layer "F.SilkS")
		)
		(fp_line
			(start 1.1938 0.4064)
			(end 0.8636 0.4064)
			(stroke
				(width 0.1)
				(type default)
			)
			(layer "F.Fab")
		)
		(fp_line
			(start 1.1938 -0.406654)
			(end 1.1938 0.4064)
			(stroke
				(width 0.1)
				(type default)
			)
			(layer "F.Fab")
		)
		(fp_line
			(start 0.8636 0.4572)
			(end -0.8636 0.4572)
			(stroke
				(width 0.1)
				(type default)
			)
			(layer "F.Fab")
		)
		(fp_line
			(start 0.8636 0.4064)
			(end 0.8636 0.4572)
			(stroke
				(width 0.1)
				(type default)
			)
			(layer "F.Fab")
		)
		(fp_line
			(start 0.8636 -0.406654)
			(end 1.1938 -0.406654)
			(stroke
				(width 0.1)
				(type default)
			)
			(layer "F.Fab")
		)
		(fp_line
			(start 0.8636 -0.4572)
			(end 0.8636 -0.406654)
			(stroke
				(width 0.1)
				(type default)
			)
			(layer "F.Fab")
		)
		(fp_line
			(start -0.8636 0.4572)
			(end -0.8636 0.4318)
			(stroke
				(width 0.1)
				(type default)
			)
			(layer "F.Fab")
		)
		(fp_line
			(start -0.8636 0.4318)
			(end -0.8636 0.4064)
			(stroke
				(width 0.1)
				(type default)
			)
			(layer "F.Fab")
		)
		(fp_line
			(start -0.8636 0.4064)
			(end -1.1938 0.4064)
			(stroke
				(width 0.1)
				(type default)
			)
			(layer "F.Fab")
		)
		(fp_line
			(start -0.8636 -0.406654)
			(end -0.8636 -0.4572)
			(stroke
				(width 0.1)
				(type default)
			)
			(layer "F.Fab")
		)
		(fp_line
			(start -0.8636 -0.4572)
			(end 0.8636 -0.4572)
			(stroke
				(width 0.1)
				(type default)
			)
			(layer "F.Fab")
		)
		(fp_line
			(start -1.1938 0.4064)
			(end -1.1938 -0.406654)
			(stroke
				(width 0.1)
				(type default)
			)
			(layer "F.Fab")
		)
		(fp_line
			(start -1.1938 -0.406654)
			(end -0.8636 -0.406654)
			(stroke
				(width 0.1)
				(type default)
			)
			(layer "F.Fab")
		)
		(pad "1" smd rect
			(at -0.7366 0 90)
			(size 0.7112 0.8128)
			(layers "F.Cu" "F.Mask" "F.Paste")
			(net "P52V_FAN_5")
		)
		(pad "2" smd rect
			(at 0.7366 0 90)
			(size 0.7112 0.8128)
			(layers "F.Cu" "F.Mask" "F.Paste")
			(net "FAN_5_TACH_IL_R")
		)
	)
	(footprint ""
		(layer "F.Cu")
		(at 4.7244 -219.329 90)
		(property "Reference" "C2038"
			(at 0 0 90)
			(layer "F.SilkS")
			(hide yes)
			(effects
				(font
					(size 1.27 1.27)
				)
			)
		)
		(property "Value" ""
			(at 0 0 90)
			(layer "F.Fab")
			(effects
				(font
					(size 1.27 1.27)
				)
			)
		)
		(duplicate_pad_numbers_are_jumpers no)
		(fp_line
			(start 1.524 -0.762)
			(end 1.524 0.762)
			(stroke
				(width 0.1524)
				(type default)
			)
			(layer "F.SilkS")
		)
		(fp_line
			(start -1.524 -0.762)
			(end 1.524 -0.762)
			(stroke
				(width 0.1524)
				(type default)
			)
			(layer "F.SilkS")
		)
		(fp_line
			(start 1.524 0.762)
			(end -1.524 0.762)
			(stroke
				(width 0.1524)
				(type default)
			)
			(layer "F.SilkS")
		)
		(fp_line
			(start -1.524 0.762)
			(end -1.524 -0.762)
			(stroke
				(width 0.1524)
				(type default)
			)
			(layer "F.SilkS")
		)
		(fp_line
			(start 1.1049 -0.724916)
			(end -1.1049 -0.724916)
			(stroke
				(width 0.1)
				(type default)
			)
			(layer "F.Fab")
		)
		(fp_line
			(start -1.1049 -0.724916)
			(end -1.1049 0.724916)
			(stroke
				(width 0.1)
				(type default)
			)
			(layer "F.Fab")
		)
		(fp_line
			(start 1.1049 0.724916)
			(end 1.1049 -0.724916)
			(stroke
				(width 0.1)
				(type default)
			)
			(layer "F.Fab")
		)
		(fp_line
			(start -1.1049 0.724916)
			(end 1.1049 0.724916)
			(stroke
				(width 0.1)
				(type default)
			)
			(layer "F.Fab")
		)
		(pad "1" smd rect
			(at -0.889 0 270)
			(size 1.016 1.27)
			(layers "F.Cu" "F.Mask" "F.Paste")
			(net "P12V_LED_FAN6")
		)
		(pad "2" smd rect
			(at 0.889 0 270)
			(size 1.016 1.27)
			(layers "F.Cu" "F.Mask" "F.Paste")
			(net "GND")
		)
	)
	(footprint ""
		(layer "F.Cu")
		(at 13.335 -164.338 180)
		(property "Reference" "R5508"
			(at 0 0 180)
			(layer "F.SilkS")
			(hide yes)
			(effects
				(font
					(size 1.27 1.27)
				)
			)
		)
		(property "Value" ""
			(at 0 0 180)
			(layer "F.Fab")
			(effects
				(font
					(size 1.27 1.27)
				)
			)
		)
		(duplicate_pad_numbers_are_jumpers no)
		(fp_line
			(start 0.7874 0.4064)
			(end -0.7874 0.4064)
			(stroke
				(width 0.1524)
				(type default)
			)
			(layer "F.SilkS")
		)
		(fp_line
			(start 0.7874 -0.4064)
			(end 0.7874 0.4064)
			(stroke
				(width 0.1524)
				(type default)
			)
			(layer "F.SilkS")
		)
		(fp_line
			(start -0.7874 0.4064)
			(end -0.7874 -0.4064)
			(stroke
				(width 0.1524)
				(type default)
			)
			(layer "F.SilkS")
		)
		(fp_line
			(start -0.7874 -0.4064)
			(end 0.7874 -0.4064)
			(stroke
				(width 0.1524)
				(type default)
			)
			(layer "F.SilkS")
		)
		(fp_line
			(start 0.67945 0.3048)
			(end 0.120396 0.3048)
			(stroke
				(width 0.1)
				(type default)
			)
			(layer "F.Fab")
		)
		(fp_line
			(start 0.67945 -0.3048)
			(end 0.67945 0.3048)
			(stroke
				(width 0.1)
				(type default)
			)
			(layer "F.Fab")
		)
		(fp_line
			(start 0.12065 -0.2794)
			(end 0.12065 -0.3048)
			(stroke
				(width 0.1)
				(type default)
			)
			(layer "F.Fab")
		)
		(fp_line
			(start 0.12065 -0.3048)
			(end 0.67945 -0.3048)
			(stroke
				(width 0.1)
				(type default)
			)
			(layer "F.Fab")
		)
		(fp_line
			(start 0.120396 0.3048)
			(end 0.120396 0.2794)
			(stroke
				(width 0.1)
				(type default)
			)
			(layer "F.Fab")
		)
		(fp_line
			(start 0.120396 0.2794)
			(end -0.12065 0.2794)
			(stroke
				(width 0.1)
				(type default)
			)
			(layer "F.Fab")
		)
		(fp_line
			(start -0.12065 0.3048)
			(end -0.67945 0.3048)
			(stroke
				(width 0.1)
				(type default)
			)
			(layer "F.Fab")
		)
		(fp_line
			(start -0.12065 0.2794)
			(end -0.12065 0.3048)
			(stroke
				(width 0.1)
				(type default)
			)
			(layer "F.Fab")
		)
		(fp_line
			(start -0.12065 -0.2794)
			(end 0.12065 -0.2794)
			(stroke
				(width 0.1)
				(type default)
			)
			(layer "F.Fab")
		)
		(fp_line
			(start -0.12065 -0.305054)
			(end -0.12065 -0.2794)
			(stroke
				(width 0.1)
				(type default)
			)
			(layer "F.Fab")
		)
		(fp_line
			(start -0.67945 0.3048)
			(end -0.67945 -0.305054)
			(stroke
				(width 0.1)
				(type default)
			)
			(layer "F.Fab")
		)
		(fp_line
			(start -0.67945 -0.305054)
			(end -0.12065 -0.305054)
			(stroke
				(width 0.1)
				(type default)
			)
			(layer "F.Fab")
		)
		(pad "1" smd circle
			(at -0.40005 0 180)
			(size 0 0)
			(layers "F.Cu" "F.Mask" "F.Paste")
			(net "P3V3_AUX")
		)
		(pad "2" smd circle
			(at 0.40005 0 180)
			(size 0 0)
			(layers "F.Cu" "F.Mask" "F.Paste")
			(net "FAN_1_PRESENT_N")
		)
	)
	(footprint ""
		(layer "F.Cu")
		(at 6.477 -169.291)
		(property "Reference" "R4852"
			(at 0 0 0)
			(layer "F.SilkS")
			(hide yes)
			(effects
				(font
					(size 1.27 1.27)
				)
			)
		)
		(property "Value" ""
			(at 0 0 0)
			(layer "F.Fab")
			(effects
				(font
					(size 1.27 1.27)
				)
			)
		)
		(duplicate_pad_numbers_are_jumpers no)
		(fp_line
			(start -0.7874 -0.4064)
			(end 0.7874 -0.4064)
			(stroke
				(width 0.1524)
				(type default)
			)
			(layer "F.SilkS")
		)
		(fp_line
			(start -0.7874 0.4064)
			(end -0.7874 -0.4064)
			(stroke
				(width 0.1524)
				(type default)
			)
			(layer "F.SilkS")
		)
		(fp_line
			(start 0.7874 -0.4064)
			(end 0.7874 0.4064)
			(stroke
				(width 0.1524)
				(type default)
			)
			(layer "F.SilkS")
		)
		(fp_line
			(start 0.7874 0.4064)
			(end -0.7874 0.4064)
			(stroke
				(width 0.1524)
				(type default)
			)
			(layer "F.SilkS")
		)
		(fp_line
			(start -0.67945 -0.305054)
			(end -0.12065 -0.305054)
			(stroke
				(width 0.1)
				(type default)
			)
			(layer "F.Fab")
		)
		(fp_line
			(start -0.67945 0.3048)
			(end -0.67945 -0.305054)
			(stroke
				(width 0.1)
				(type default)
			)
			(layer "F.Fab")
		)
		(fp_line
			(start -0.12065 -0.305054)
			(end -0.12065 -0.2794)
			(stroke
				(width 0.1)
				(type default)
			)
			(layer "F.Fab")
		)
		(fp_line
			(start -0.12065 -0.2794)
			(end 0.12065 -0.2794)
			(stroke
				(width 0.1)
				(type default)
			)
			(layer "F.Fab")
		)
		(fp_line
			(start -0.12065 0.2794)
			(end -0.12065 0.3048)
			(stroke
				(width 0.1)
				(type default)
			)
			(layer "F.Fab")
		)
		(fp_line
			(start -0.12065 0.3048)
			(end -0.67945 0.3048)
			(stroke
				(width 0.1)
				(type default)
			)
			(layer "F.Fab")
		)
		(fp_line
			(start 0.120396 0.2794)
			(end -0.12065 0.2794)
			(stroke
				(width 0.1)
				(type default)
			)
			(layer "F.Fab")
		)
		(fp_line
			(start 0.120396 0.3048)
			(end 0.120396 0.2794)
			(stroke
				(width 0.1)
				(type default)
			)
			(layer "F.Fab")
		)
		(fp_line
			(start 0.12065 -0.3048)
			(end 0.67945 -0.3048)
			(stroke
				(width 0.1)
				(type default)
			)
			(layer "F.Fab")
		)
		(fp_line
			(start 0.12065 -0.2794)
			(end 0.12065 -0.3048)
			(stroke
				(width 0.1)
				(type default)
			)
			(layer "F.Fab")
		)
		(fp_line
			(start 0.67945 -0.3048)
			(end 0.67945 0.3048)
			(stroke
				(width 0.1)
				(type default)
			)
			(layer "F.Fab")
		)
		(fp_line
			(start 0.67945 0.3048)
			(end 0.120396 0.3048)
			(stroke
				(width 0.1)
				(type default)
			)
			(layer "F.Fab")
		)
		(pad "1" smd circle
			(at -0.40005 0)
			(size 0 0)
			(layers "F.Cu" "F.Mask" "F.Paste")
			(net "P3V3_AUX")
		)
		(pad "2" smd circle
			(at 0.40005 0)
			(size 0 0)
			(layers "F.Cu" "F.Mask" "F.Paste")
			(net "FAN_4_PRSNT_BUF_R_N")
		)
	)
	(footprint ""
		(layer "F.Cu")
		(at 37.338 -205.895956)
		(property "Reference" "R5202"
			(at 0 0 0)
			(layer "F.SilkS")
			(hide yes)
			(effects
				(font
					(size 1.27 1.27)
				)
			)
		)
		(property "Value" ""
			(at 0 0 0)
			(layer "F.Fab")
			(effects
				(font
					(size 1.27 1.27)
				)
			)
		)
		(duplicate_pad_numbers_are_jumpers no)
		(fp_line
			(start -0.7874 -0.4064)
			(end 0.7874 -0.4064)
			(stroke
				(width 0.1524)
				(type default)
			)
			(layer "F.SilkS")
		)
		(fp_line
			(start -0.7874 0.4064)
			(end -0.7874 -0.4064)
			(stroke
				(width 0.1524)
				(type default)
			)
			(layer "F.SilkS")
		)
		(fp_line
			(start 0.7874 -0.4064)
			(end 0.7874 0.4064)
			(stroke
				(width 0.1524)
				(type default)
			)
			(layer "F.SilkS")
		)
		(fp_line
			(start 0.7874 0.4064)
			(end -0.7874 0.4064)
			(stroke
				(width 0.1524)
				(type default)
			)
			(layer "F.SilkS")
		)
		(fp_line
			(start -0.67945 -0.305054)
			(end -0.12065 -0.305054)
			(stroke
				(width 0.1)
				(type default)
			)
			(layer "F.Fab")
		)
		(fp_line
			(start -0.67945 0.3048)
			(end -0.67945 -0.305054)
			(stroke
				(width 0.1)
				(type default)
			)
			(layer "F.Fab")
		)
		(fp_line
			(start -0.12065 -0.305054)
			(end -0.12065 -0.2794)
			(stroke
				(width 0.1)
				(type default)
			)
			(layer "F.Fab")
		)
		(fp_line
			(start -0.12065 -0.2794)
			(end 0.12065 -0.2794)
			(stroke
				(width 0.1)
				(type default)
			)
			(layer "F.Fab")
		)
		(fp_line
			(start -0.12065 0.2794)
			(end -0.12065 0.3048)
			(stroke
				(width 0.1)
				(type default)
			)
			(layer "F.Fab")
		)
		(fp_line
			(start -0.12065 0.3048)
			(end -0.67945 0.3048)
			(stroke
				(width 0.1)
				(type default)
			)
			(layer "F.Fab")
		)
		(fp_line
			(start 0.120396 0.2794)
			(end -0.12065 0.2794)
			(stroke
				(width 0.1)
				(type default)
			)
			(layer "F.Fab")
		)
		(fp_line
			(start 0.120396 0.3048)
			(end 0.120396 0.2794)
			(stroke
				(width 0.1)
				(type default)
			)
			(layer "F.Fab")
		)
		(fp_line
			(start 0.12065 -0.3048)
			(end 0.67945 -0.3048)
			(stroke
				(width 0.1)
				(type default)
			)
			(layer "F.Fab")
		)
		(fp_line
			(start 0.12065 -0.2794)
			(end 0.12065 -0.3048)
			(stroke
				(width 0.1)
				(type default)
			)
			(layer "F.Fab")
		)
		(fp_line
			(start 0.67945 -0.3048)
			(end 0.67945 0.3048)
			(stroke
				(width 0.1)
				(type default)
			)
			(layer "F.Fab")
		)
		(fp_line
			(start 0.67945 0.3048)
			(end 0.120396 0.3048)
			(stroke
				(width 0.1)
				(type default)
			)
			(layer "F.Fab")
		)
		(pad "1" smd circle
			(at -0.40005 0)
			(size 0 0)
			(layers "F.Cu" "F.Mask" "F.Paste")
			(net "SMB_FAN1_SCL")
		)
		(pad "2" smd circle
			(at 0.40005 0)
			(size 0 0)
			(layers "F.Cu" "F.Mask" "F.Paste")
			(net "SMB_FAN1_SCL_R")
		)
	)
	(footprint ""
		(layer "F.Cu")
		(at 7.112 -65.913)
		(property "Reference" "PR47"
			(at 0 0 0)
			(layer "F.SilkS")
			(hide yes)
			(effects
				(font
					(size 1.27 1.27)
				)
			)
		)
		(property "Value" ""
			(at 0 0 0)
			(layer "F.Fab")
			(effects
				(font
					(size 1.27 1.27)
				)
			)
		)
		(duplicate_pad_numbers_are_jumpers no)
		(fp_line
			(start -0.7874 -0.4064)
			(end 0.7874 -0.4064)
			(stroke
				(width 0.1524)
				(type default)
			)
			(layer "F.SilkS")
		)
		(fp_line
			(start -0.7874 0.4064)
			(end -0.7874 -0.4064)
			(stroke
				(width 0.1524)
				(type default)
			)
			(layer "F.SilkS")
		)
		(fp_line
			(start 0.7874 -0.4064)
			(end 0.7874 0.4064)
			(stroke
				(width 0.1524)
				(type default)
			)
			(layer "F.SilkS")
		)
		(fp_line
			(start 0.7874 0.4064)
			(end -0.7874 0.4064)
			(stroke
				(width 0.1524)
				(type default)
			)
			(layer "F.SilkS")
		)
		(fp_line
			(start -0.67945 -0.305054)
			(end -0.12065 -0.305054)
			(stroke
				(width 0.1)
				(type default)
			)
			(layer "F.Fab")
		)
		(fp_line
			(start -0.67945 0.3048)
			(end -0.67945 -0.305054)
			(stroke
				(width 0.1)
				(type default)
			)
			(layer "F.Fab")
		)
		(fp_line
			(start -0.12065 -0.305054)
			(end -0.12065 -0.2794)
			(stroke
				(width 0.1)
				(type default)
			)
			(layer "F.Fab")
		)
		(fp_line
			(start -0.12065 -0.2794)
			(end 0.12065 -0.2794)
			(stroke
				(width 0.1)
				(type default)
			)
			(layer "F.Fab")
		)
		(fp_line
			(start -0.12065 0.2794)
			(end -0.12065 0.3048)
			(stroke
				(width 0.1)
				(type default)
			)
			(layer "F.Fab")
		)
		(fp_line
			(start -0.12065 0.3048)
			(end -0.67945 0.3048)
			(stroke
				(width 0.1)
				(type default)
			)
			(layer "F.Fab")
		)
		(fp_line
			(start 0.120396 0.2794)
			(end -0.12065 0.2794)
			(stroke
				(width 0.1)
				(type default)
			)
			(layer "F.Fab")
		)
		(fp_line
			(start 0.120396 0.3048)
			(end 0.120396 0.2794)
			(stroke
				(width 0.1)
				(type default)
			)
			(layer "F.Fab")
		)
		(fp_line
			(start 0.12065 -0.3048)
			(end 0.67945 -0.3048)
			(stroke
				(width 0.1)
				(type default)
			)
			(layer "F.Fab")
		)
		(fp_line
			(start 0.12065 -0.2794)
			(end 0.12065 -0.3048)
			(stroke
				(width 0.1)
				(type default)
			)
			(layer "F.Fab")
		)
		(fp_line
			(start 0.67945 -0.3048)
			(end 0.67945 0.3048)
			(stroke
				(width 0.1)
				(type default)
			)
			(layer "F.Fab")
		)
		(fp_line
			(start 0.67945 0.3048)
			(end 0.120396 0.3048)
			(stroke
				(width 0.1)
				(type default)
			)
			(layer "F.Fab")
		)
		(pad "1" smd circle
			(at -0.40005 0)
			(size 0 0)
			(layers "F.Cu" "F.Mask" "F.Paste")
			(net "FAN_4_FAULT_R")
		)
		(pad "2" smd circle
			(at 0.40005 0)
			(size 0 0)
			(layers "F.Cu" "F.Mask" "F.Paste")
			(net "FAN_4_P3V_R")
		)
	)
	(footprint ""
		(layer "F.Cu")
		(at 5.969 -250.317)
		(property "Reference" "PR63"
			(at 0 0 0)
			(layer "F.SilkS")
			(hide yes)
			(effects
				(font
					(size 1.27 1.27)
				)
			)
		)
		(property "Value" ""
			(at 0 0 0)
			(layer "F.Fab")
			(effects
				(font
					(size 1.27 1.27)
				)
			)
		)
		(duplicate_pad_numbers_are_jumpers no)
		(fp_line
			(start -0.7874 -0.4064)
			(end 0.7874 -0.4064)
			(stroke
				(width 0.1524)
				(type default)
			)
			(layer "F.SilkS")
		)
		(fp_line
			(start -0.7874 0.4064)
			(end -0.7874 -0.4064)
			(stroke
				(width 0.1524)
				(type default)
			)
			(layer "F.SilkS")
		)
		(fp_line
			(start 0.7874 -0.4064)
			(end 0.7874 0.4064)
			(stroke
				(width 0.1524)
				(type default)
			)
			(layer "F.SilkS")
		)
		(fp_line
			(start 0.7874 0.4064)
			(end -0.7874 0.4064)
			(stroke
				(width 0.1524)
				(type default)
			)
			(layer "F.SilkS")
		)
		(fp_line
			(start -0.67945 -0.305054)
			(end -0.12065 -0.305054)
			(stroke
				(width 0.1)
				(type default)
			)
			(layer "F.Fab")
		)
		(fp_line
			(start -0.67945 0.3048)
			(end -0.67945 -0.305054)
			(stroke
				(width 0.1)
				(type default)
			)
			(layer "F.Fab")
		)
		(fp_line
			(start -0.12065 -0.305054)
			(end -0.12065 -0.2794)
			(stroke
				(width 0.1)
				(type default)
			)
			(layer "F.Fab")
		)
		(fp_line
			(start -0.12065 -0.2794)
			(end 0.12065 -0.2794)
			(stroke
				(width 0.1)
				(type default)
			)
			(layer "F.Fab")
		)
		(fp_line
			(start -0.12065 0.2794)
			(end -0.12065 0.3048)
			(stroke
				(width 0.1)
				(type default)
			)
			(layer "F.Fab")
		)
		(fp_line
			(start -0.12065 0.3048)
			(end -0.67945 0.3048)
			(stroke
				(width 0.1)
				(type default)
			)
			(layer "F.Fab")
		)
		(fp_line
			(start 0.120396 0.2794)
			(end -0.12065 0.2794)
			(stroke
				(width 0.1)
				(type default)
			)
			(layer "F.Fab")
		)
		(fp_line
			(start 0.120396 0.3048)
			(end 0.120396 0.2794)
			(stroke
				(width 0.1)
				(type default)
			)
			(layer "F.Fab")
		)
		(fp_line
			(start 0.12065 -0.3048)
			(end 0.67945 -0.3048)
			(stroke
				(width 0.1)
				(type default)
			)
			(layer "F.Fab")
		)
		(fp_line
			(start 0.12065 -0.2794)
			(end 0.12065 -0.3048)
			(stroke
				(width 0.1)
				(type default)
			)
			(layer "F.Fab")
		)
		(fp_line
			(start 0.67945 -0.3048)
			(end 0.67945 0.3048)
			(stroke
				(width 0.1)
				(type default)
			)
			(layer "F.Fab")
		)
		(fp_line
			(start 0.67945 0.3048)
			(end 0.120396 0.3048)
			(stroke
				(width 0.1)
				(type default)
			)
			(layer "F.Fab")
		)
		(pad "1" smd circle
			(at -0.40005 0)
			(size 0 0)
			(layers "F.Cu" "F.Mask" "F.Paste")
			(net "FAN_6_FAULT_R")
		)
		(pad "2" smd circle
			(at 0.40005 0)
			(size 0 0)
			(layers "F.Cu" "F.Mask" "F.Paste")
			(net "FAN_6_P3V_R")
		)
	)
)
